# T6G (Grand Teton) — schematic netlist excerpt (pin names and nets, part order shuffled) for the footprints in the layout excerpt that follows; sources: Cadence DE-HDL packaged netlist, KiCad conversion of 04192023_DAF0TMB3IC0_F0TG_MB_C_brd_V02_OCP.brd

R2204  Q_RES  2.2K 5% EMPTY  pkg 0402LF  page 250 : A = P3V3_AUX ; B = SMB_PCIE0_3V3AUX_SCL
R361  Q_RES  4.7K 5% EMPTY  pkg 0402LF  page 160 : A = P3V3 ; B = SMB_CPU0_CPU1_APML_BUF1_SCL_R2

(kicad_pcb
	(version 20260206)
	(generator "pcbnew")
	(generator_version "10.0")
	(general
		(thickness 1.6)
		(legacy_teardrops no)
	)
	(paper "A4")
	(title_block
		(title "04192023_DAF0TMB3IC0_F0TG_MB_C_brd_V02_OCP.brd")
		(comment 1 "Grand Teton / footprints 5382-5383 of 8354")
	)
	(layers
		(0 "F.Cu" signal "TOP")
		(4 "In1.Cu" signal "GND")
		(6 "In2.Cu" signal "IN1")
		(8 "In3.Cu" signal "GND1")
		(10 "In4.Cu" signal "IN2")
		(12 "In5.Cu" signal "GND2")
		(14 "In6.Cu" signal "IN3")
		(16 "In7.Cu" signal "GND3")
		(18 "In8.Cu" signal "VCC")
		(20 "In9.Cu" signal "VCC1")
		(22 "In10.Cu" signal "GND4")
		(24 "In11.Cu" signal "IN4")
		(26 "In12.Cu" signal "GND5")
		(28 "In13.Cu" signal "IN5")
		(30 "In14.Cu" signal "GND6")
		(32 "In15.Cu" signal "IN6")
		(34 "In16.Cu" signal "GND7")
		(2 "B.Cu" signal "BOTTOM")
		(9 "F.Adhes" user "F.Adhesive")
		(11 "B.Adhes" user "B.Adhesive")
		(13 "F.Paste" user "Package Geometry/Pastemask Top")
		(15 "B.Paste" user "Package Geometry/Pastemask Bottom")
		(5 "F.SilkS" user "Ref Des/Silkscreen Top")
		(7 "B.SilkS" user "Ref Des/Silkscreen Bottom")
		(1 "F.Mask" user "Board Geometry/Soldermask Top")
		(3 "B.Mask" user "Board Geometry/Soldermask Bottom")
		(17 "Dwgs.User" user "User.Drawings")
		(19 "Cmts.User" user "User.Comments")
		(21 "Eco1.User" user "User.Eco1")
		(23 "Eco2.User" user "User.Eco2")
		(25 "Edge.Cuts" user "Board Geometry/Outline")
		(27 "Margin" user)
		(31 "F.CrtYd" user "Package Geometry/Place Bound Top")
		(29 "B.CrtYd" user "Package Geometry/Place Bound Bottom")
		(35 "F.Fab" user "Ref Des/Assembly Top")
		(33 "B.Fab" user "Ref Des/Assembly Bottom")
	)
	(footprint ""
		(layer "B.Cu")
		(at 166.696644 -9.013444 -90)
		(property "Reference" "R2204"
			(at 0 0 90)
			(layer "B.SilkS")
			(hide yes)
			(effects
				(font
					(size 1.27 1.27)
				)
				(justify mirror)
			)
		)
		(property "Value" ""
			(at 0 0 90)
			(layer "B.Fab")
			(effects
				(font
					(size 1.27 1.27)
				)
				(justify mirror)
			)
		)
		(duplicate_pad_numbers_are_jumpers no)
		(fp_line
			(start -0.7874 0.4064)
			(end 0.7874 0.4064)
			(stroke
				(width 0.1524)
				(type default)
			)
			(layer "B.SilkS")
		)
		(fp_line
			(start 0.7874 0.4064)
			(end 0.7874 -0.4064)
			(stroke
				(width 0.1524)
				(type default)
			)
			(layer "B.SilkS")
		)
		(fp_line
			(start -0.7874 -0.4064)
			(end -0.7874 0.4064)
			(stroke
				(width 0.1524)
				(type default)
			)
			(layer "B.SilkS")
		)
		(fp_line
			(start 0.7874 -0.4064)
			(end -0.7874 -0.4064)
			(stroke
				(width 0.1524)
				(type default)
			)
			(layer "B.SilkS")
		)
		(fp_line
			(start -0.67945 0.3048)
			(end -0.120396 0.3048)
			(stroke
				(width 0.1)
				(type default)
			)
			(layer "B.Fab")
		)
		(fp_line
			(start -0.120396 0.3048)
			(end -0.120396 0.2794)
			(stroke
				(width 0.1)
				(type default)
			)
			(layer "B.Fab")
		)
		(fp_line
			(start 0.12065 0.3048)
			(end 0.67945 0.3048)
			(stroke
				(width 0.1)
				(type default)
			)
			(layer "B.Fab")
		)
		(fp_line
			(start 0.67945 0.3048)
			(end 0.67945 -0.305054)
			(stroke
				(width 0.1)
				(type default)
			)
			(layer "B.Fab")
		)
		(fp_line
			(start -0.120396 0.2794)
			(end 0.12065 0.2794)
			(stroke
				(width 0.1)
				(type default)
			)
			(layer "B.Fab")
		)
		(fp_line
			(start 0.12065 0.2794)
			(end 0.12065 0.3048)
			(stroke
				(width 0.1)
				(type default)
			)
			(layer "B.Fab")
		)
		(fp_line
			(start -0.12065 -0.2794)
			(end -0.12065 -0.3048)
			(stroke
				(width 0.1)
				(type default)
			)
			(layer "B.Fab")
		)
		(fp_line
			(start 0.12065 -0.2794)
			(end -0.12065 -0.2794)
			(stroke
				(width 0.1)
				(type default)
			)
			(layer "B.Fab")
		)
		(fp_line
			(start -0.67945 -0.3048)
			(end -0.67945 0.3048)
			(stroke
				(width 0.1)
				(type default)
			)
			(layer "B.Fab")
		)
		(fp_line
			(start -0.12065 -0.3048)
			(end -0.67945 -0.3048)
			(stroke
				(width 0.1)
				(type default)
			)
			(layer "B.Fab")
		)
		(fp_line
			(start 0.12065 -0.305054)
			(end 0.12065 -0.2794)
			(stroke
				(width 0.1)
				(type default)
			)
			(layer "B.Fab")
		)
		(fp_line
			(start 0.67945 -0.305054)
			(end 0.12065 -0.305054)
			(stroke
				(width 0.1)
				(type default)
			)
			(layer "B.Fab")
		)
		(pad "1" smd circle
			(at 0.40005 0 90)
			(size 0 0)
			(layers "B.Cu" "B.Mask" "B.Paste")
			(net "P3V3_AUX")
		)
		(pad "2" smd circle
			(at -0.40005 0 90)
			(size 0 0)
			(layers "B.Cu" "B.Mask" "B.Paste")
			(net "SMB_PCIE0_3V3AUX_SCL")
		)
	)
	(footprint ""
		(layer "B.Cu")
		(at 237.871 -216.027 180)
		(property "Reference" "R361"
			(at 0 0 0)
			(layer "B.SilkS")
			(hide yes)
			(effects
				(font
					(size 1.27 1.27)
				)
				(justify mirror)
			)
		)
		(property "Value" ""
			(at 0 0 0)
			(layer "B.Fab")
			(effects
				(font
					(size 1.27 1.27)
				)
				(justify mirror)
			)
		)
		(duplicate_pad_numbers_are_jumpers no)
		(fp_line
			(start 0.7874 0.4064)
			(end 0.7874 -0.4064)
			(stroke
				(width 0.1524)
				(type default)
			)
			(layer "B.SilkS")
		)
		(fp_line
			(start 0.7874 -0.4064)
			(end -0.7874 -0.4064)
			(stroke
				(width 0.1524)
				(type default)
			)
			(layer "B.SilkS")
		)
		(fp_line
			(start -0.7874 0.4064)
			(end 0.7874 0.4064)
			(stroke
				(width 0.1524)
				(type default)
			)
			(layer "B.SilkS")
		)
		(fp_line
			(start -0.7874 -0.4064)
			(end -0.7874 0.4064)
			(stroke
				(width 0.1524)
				(type default)
			)
			(layer "B.SilkS")
		)
		(fp_line
			(start 0.67945 0.3048)
			(end 0.67945 -0.305054)
			(stroke
				(width 0.1)
				(type default)
			)
			(layer "B.Fab")
		)
		(fp_line
			(start 0.67945 -0.305054)
			(end 0.12065 -0.305054)
			(stroke
				(width 0.1)
				(type default)
			)
			(layer "B.Fab")
		)
		(fp_line
			(start 0.12065 0.3048)
			(end 0.67945 0.3048)
			(stroke
				(width 0.1)
				(type default)
			)
			(layer "B.Fab")
		)
		(fp_line
			(start 0.12065 0.2794)
			(end 0.12065 0.3048)
			(stroke
				(width 0.1)
				(type default)
			)
			(layer "B.Fab")
		)
		(fp_line
			(start 0.12065 -0.2794)
			(end -0.12065 -0.2794)
			(stroke
				(width 0.1)
				(type default)
			)
			(layer "B.Fab")
		)
		(fp_line
			(start 0.12065 -0.305054)
			(end 0.12065 -0.2794)
			(stroke
				(width 0.1)
				(type default)
			)
			(layer "B.Fab")
		)
		(fp_line
			(start -0.120396 0.3048)
			(end -0.120396 0.2794)
			(stroke
				(width 0.1)
				(type default)
			)
			(layer "B.Fab")
		)
		(fp_line
			(start -0.120396 0.2794)
			(end 0.12065 0.2794)
			(stroke
				(width 0.1)
				(type default)
			)
			(layer "B.Fab")
		)
		(fp_line
			(start -0.12065 -0.2794)
			(end -0.12065 -0.3048)
			(stroke
				(width 0.1)
				(type default)
			)
			(layer "B.Fab")
		)
		(fp_line
			(start -0.12065 -0.3048)
			(end -0.67945 -0.3048)
			(stroke
				(width 0.1)
				(type default)
			)
			(layer "B.Fab")
		)
		(fp_line
			(start -0.67945 0.3048)
			(end -0.120396 0.3048)
			(stroke
				(width 0.1)
				(type default)
			)
			(layer "B.Fab")
		)
		(fp_line
			(start -0.67945 -0.3048)
			(end -0.67945 0.3048)
			(stroke
				(width 0.1)
				(type default)
			)
			(layer "B.Fab")
		)
		(pad "1" smd circle
			(at 0.40005 0)
			(size 0 0)
			(layers "B.Cu" "B.Mask" "B.Paste")
			(net "P3V3")
		)
		(pad "2" smd circle
			(at -0.40005 0)
			(size 0 0)
			(layers "B.Cu" "B.Mask" "B.Paste")
			(net "SMB_CPU0_CPU1_APML_BUF1_SCL_R2")
		)
	)
)
